(kicad_pcb
	(version 20260206)
	(generator "pcbnew")
	(generator_version "10.0")
	(general
		(thickness 1.6)
		(legacy_teardrops no)
	)
	(paper "A4")
	(title_block
		(title "Wiwynn_Tioga_Pass_MB.brd")
		(comment 1 "Tioga Pass / footprints 667-673 of 4770")
	)
	(layers
		(0 "F.Cu" signal "TOP")
		(4 "In1.Cu" signal "L2GND")
		(6 "In2.Cu" signal "L3")
		(8 "In3.Cu" signal "L4GND")
		(10 "In4.Cu" signal "L5")
		(12 "In5.Cu" signal "L6GND")
		(14 "In6.Cu" signal "L7VCC")
		(16 "In7.Cu" signal "L8VCC")
		(18 "In8.Cu" signal "L9GND")
		(20 "In9.Cu" signal "L10")
		(22 "In10.Cu" signal "L11GND")
		(24 "In11.Cu" signal "L12")
		(26 "In12.Cu" signal "L13GND")
		(2 "B.Cu" signal "BOTTOM")
		(9 "F.Adhes" user "F.Adhesive")
		(11 "B.Adhes" user "B.Adhesive")
		(13 "F.Paste" user "Package Geometry/Pastemask Top")
		(15 "B.Paste" user "Package Geometry/Pastemask Bottom")
		(5 "F.SilkS" user "Ref Des/Silkscreen Top")
		(7 "B.SilkS" user "Ref Des/Silkscreen Bottom")
		(1 "F.Mask" user "Board Geometry/Soldermask Top")
		(3 "B.Mask" user "Board Geometry/Soldermask Bottom")
		(17 "Dwgs.User" user "User.Drawings")
		(19 "Cmts.User" user "User.Comments")
		(21 "Eco1.User" user "User.Eco1")
		(23 "Eco2.User" user "User.Eco2")
		(25 "Edge.Cuts" user "Board Geometry/Outline")
		(27 "Margin" user)
		(31 "F.CrtYd" user "Package Geometry/Place Bound Top")
		(29 "B.CrtYd" user "Package Geometry/Place Bound Bottom")
		(35 "F.Fab" user "Ref Des/Assembly Top")
		(33 "B.Fab" user "Ref Des/Assembly Bottom")
	)
	(footprint ""
		(layer "F.Cu")
		(at 459.3336 -30.6832)
		(property "Reference" "R1U5"
			(at 0 0 0)
			(layer "F.SilkS")
			(hide yes)
			(effects
				(font
					(size 1.27 1.27)
				)
			)
		)
		(property "Value" ""
			(at 0 0 0)
			(layer "F.Fab")
			(effects
				(font
					(size 1.27 1.27)
				)
			)
		)
		(duplicate_pad_numbers_are_jumpers no)
		(fp_poly
			(pts
				(xy -0.2794 -0.1016) (xy 0.2794 -0.1016) (xy 0.2794 0.9906) (xy -0.2794 0.9906)
			)
			(stroke
				(width 0)
				(type default)
			)
			(fill no)
			(layer "F.CrtYd")
		)
		(fp_line
			(start -0.2794 -0.1016)
			(end -0.2794 0.9906)
			(stroke
				(width 0.1)
				(type default)
			)
			(layer "F.Fab")
		)
		(fp_line
			(start -0.2794 0.9906)
			(end 0.2794 0.9906)
			(stroke
				(width 0.1)
				(type default)
			)
			(layer "F.Fab")
		)
		(fp_line
			(start 0.2794 -0.1016)
			(end -0.2794 -0.1016)
			(stroke
				(width 0.1)
				(type default)
			)
			(layer "F.Fab")
		)
		(fp_line
			(start 0.2794 0.9906)
			(end 0.2794 -0.1016)
			(stroke
				(width 0.1)
				(type default)
			)
			(layer "F.Fab")
		)
		(pad "1" smd rect
			(at 0 0)
			(size 0.508 0.508)
			(layers "F.Cu" "F.Mask" "F.Paste")
			(net "FAN_TACH0")
		)
		(pad "2" smd rect
			(at 0 0.889)
			(size 0.508 0.508)
			(layers "F.Cu" "F.Mask" "F.Paste")
			(net "GND")
		)
		(zone
			(layer "F.Cu")
			(hatch none 0.5)
			(connect_pads
				(clearance 0)
			)
			(min_thickness 0.25)
			(keepout
				(tracks allowed)
				(vias not_allowed)
				(pads allowed)
				(copperpour not_allowed)
				(footprints allowed)
			)
			(placement
				(enabled no)
				(sheetname "")
			)
			(fill
				(thermal_gap 0.5)
				(thermal_bridge_width 0.5)
				(island_removal_mode 0)
			)
			(polygon
				(pts
					(xy 459.0796 -30.4292) (xy 459.5876 -30.4292) (xy 459.5876 -30.0482) (xy 459.0796 -30.0482)
				)
			)
		)
		(zone
			(layer "F.Cu")
			(hatch none 0.5)
			(connect_pads
				(clearance 0)
			)
			(min_thickness 0.25)
			(keepout
				(tracks not_allowed)
				(vias allowed)
				(pads allowed)
				(copperpour not_allowed)
				(footprints allowed)
			)
			(placement
				(enabled no)
				(sheetname "")
			)
			(fill
				(thermal_gap 0.5)
				(thermal_bridge_width 0.5)
				(island_removal_mode 0)
			)
			(polygon
				(pts
					(xy 459.0796 -30.0482) (xy 459.5876 -30.0482) (xy 459.5876 -30.4292) (xy 459.0796 -30.4292)
				)
			)
		)
	)
	(footprint ""
		(layer "F.Cu")
		(at 490.7153 -49.8094 90)
		(property "Reference" "R9E5"
			(at 0 0 90)
			(layer "F.SilkS")
			(hide yes)
			(effects
				(font
					(size 1.27 1.27)
				)
			)
		)
		(property "Value" ""
			(at 0 0 90)
			(layer "F.Fab")
			(effects
				(font
					(size 1.27 1.27)
				)
			)
		)
		(duplicate_pad_numbers_are_jumpers no)
		(fp_poly
			(pts
				(xy -0.2794 -0.1016) (xy 0.2794 -0.1016) (xy 0.2794 0.9906) (xy -0.2794 0.9906)
			)
			(stroke
				(width 0)
				(type default)
			)
			(fill no)
			(layer "F.CrtYd")
		)
		(fp_line
			(start 0.2794 -0.1016)
			(end -0.2794 -0.1016)
			(stroke
				(width 0.1)
				(type default)
			)
			(layer "F.Fab")
		)
		(fp_line
			(start -0.2794 -0.1016)
			(end -0.2794 0.9906)
			(stroke
				(width 0.1)
				(type default)
			)
			(layer "F.Fab")
		)
		(fp_line
			(start 0.2794 0.9906)
			(end 0.2794 -0.1016)
			(stroke
				(width 0.1)
				(type default)
			)
			(layer "F.Fab")
		)
		(fp_line
			(start -0.2794 0.9906)
			(end 0.2794 0.9906)
			(stroke
				(width 0.1)
				(type default)
			)
			(layer "F.Fab")
		)
		(pad "1" smd rect
			(at 0 0 90)
			(size 0.508 0.508)
			(layers "F.Cu" "F.Mask" "F.Paste")
			(net "SPI_NIC_CS_R_N")
		)
		(pad "2" smd rect
			(at 0 0.889 90)
			(size 0.508 0.508)
			(layers "F.Cu" "F.Mask" "F.Paste")
			(net "SPI_NIC_CS_N")
		)
		(zone
			(layer "F.Cu")
			(hatch none 0.5)
			(connect_pads
				(clearance 0)
			)
			(min_thickness 0.25)
			(keepout
				(tracks allowed)
				(vias not_allowed)
				(pads allowed)
				(copperpour not_allowed)
				(footprints allowed)
			)
			(placement
				(enabled no)
				(sheetname "")
			)
			(fill
				(thermal_gap 0.5)
				(thermal_bridge_width 0.5)
				(island_removal_mode 0)
			)
			(polygon
				(pts
					(xy 490.9693 -49.5554) (xy 490.9693 -50.0634) (xy 491.3503 -50.0634) (xy 491.3503 -49.5554)
				)
			)
		)
		(zone
			(layer "F.Cu")
			(hatch none 0.5)
			(connect_pads
				(clearance 0)
			)
			(min_thickness 0.25)
			(keepout
				(tracks not_allowed)
				(vias allowed)
				(pads allowed)
				(copperpour not_allowed)
				(footprints allowed)
			)
			(placement
				(enabled no)
				(sheetname "")
			)
			(fill
				(thermal_gap 0.5)
				(thermal_bridge_width 0.5)
				(island_removal_mode 0)
			)
			(polygon
				(pts
					(xy 491.3503 -49.5554) (xy 491.3503 -50.0634) (xy 490.9693 -50.0634) (xy 490.9693 -49.5554)
				)
			)
		)
	)
	(footprint ""
		(layer "F.Cu")
		(at 431.8 -26.797)
		(property "Reference" "R25W157"
			(at -0.8382 -0.67818 0)
			(unlocked yes)
			(layer "F.SilkS")
			(effects
				(font
					(size 0.4064 0.254)
					(thickness 0.1524)
				)
				(justify left)
			)
		)
		(property "Value" ""
			(at 0 0 0)
			(layer "F.Fab")
			(effects
				(font
					(size 1.27 1.27)
				)
			)
		)
		(duplicate_pad_numbers_are_jumpers no)
		(fp_poly
			(pts
				(xy -0.2794 -0.1016) (xy 0.2794 -0.1016) (xy 0.2794 0.9906) (xy -0.2794 0.9906)
			)
			(stroke
				(width 0)
				(type default)
			)
			(fill no)
			(layer "F.CrtYd")
		)
		(fp_line
			(start -0.2794 -0.1016)
			(end -0.2794 0.9906)
			(stroke
				(width 0.1)
				(type default)
			)
			(layer "F.Fab")
		)
		(fp_line
			(start -0.2794 0.9906)
			(end 0.2794 0.9906)
			(stroke
				(width 0.1)
				(type default)
			)
			(layer "F.Fab")
		)
		(fp_line
			(start 0.2794 -0.1016)
			(end -0.2794 -0.1016)
			(stroke
				(width 0.1)
				(type default)
			)
			(layer "F.Fab")
		)
		(fp_line
			(start 0.2794 0.9906)
			(end 0.2794 -0.1016)
			(stroke
				(width 0.1)
				(type default)
			)
			(layer "F.Fab")
		)
		(pad "1" smd rect
			(at 0 0)
			(size 0.508 0.508)
			(layers "F.Cu" "F.Mask" "F.Paste")
			(net "PUMP_TACH0")
		)
		(pad "2" smd rect
			(at 0 0.889)
			(size 0.508 0.508)
			(layers "F.Cu" "F.Mask" "F.Paste")
			(net "GND")
		)
		(zone
			(layer "F.Cu")
			(hatch none 0.5)
			(connect_pads
				(clearance 0)
			)
			(min_thickness 0.25)
			(keepout
				(tracks allowed)
				(vias not_allowed)
				(pads allowed)
				(copperpour not_allowed)
				(footprints allowed)
			)
			(placement
				(enabled no)
				(sheetname "")
			)
			(fill
				(thermal_gap 0.5)
				(thermal_bridge_width 0.5)
				(island_removal_mode 0)
			)
			(polygon
				(pts
					(xy 431.546 -26.543) (xy 432.054 -26.543) (xy 432.054 -26.162) (xy 431.546 -26.162)
				)
			)
		)
		(zone
			(layer "F.Cu")
			(hatch none 0.5)
			(connect_pads
				(clearance 0)
			)
			(min_thickness 0.25)
			(keepout
				(tracks not_allowed)
				(vias allowed)
				(pads allowed)
				(copperpour not_allowed)
				(footprints allowed)
			)
			(placement
				(enabled no)
				(sheetname "")
			)
			(fill
				(thermal_gap 0.5)
				(thermal_bridge_width 0.5)
				(island_removal_mode 0)
			)
			(polygon
				(pts
					(xy 431.546 -26.162) (xy 432.054 -26.162) (xy 432.054 -26.543) (xy 431.546 -26.543)
				)
			)
		)
	)
	(footprint ""
		(layer "F.Cu")
		(at 436.8165 -16.129 90)
		(property "Reference" "R1U35"
			(at 0 0 90)
			(layer "F.SilkS")
			(hide yes)
			(effects
				(font
					(size 1.27 1.27)
				)
			)
		)
		(property "Value" ""
			(at 0 0 90)
			(layer "F.Fab")
			(effects
				(font
					(size 1.27 1.27)
				)
			)
		)
		(duplicate_pad_numbers_are_jumpers no)
		(fp_poly
			(pts
				(xy -0.2794 -0.1016) (xy 0.2794 -0.1016) (xy 0.2794 0.9906) (xy -0.2794 0.9906)
			)
			(stroke
				(width 0)
				(type default)
			)
			(fill no)
			(layer "F.CrtYd")
		)
		(fp_line
			(start 0.2794 -0.1016)
			(end -0.2794 -0.1016)
			(stroke
				(width 0.1)
				(type default)
			)
			(layer "F.Fab")
		)
		(fp_line
			(start -0.2794 -0.1016)
			(end -0.2794 0.9906)
			(stroke
				(width 0.1)
				(type default)
			)
			(layer "F.Fab")
		)
		(fp_line
			(start 0.2794 0.9906)
			(end 0.2794 -0.1016)
			(stroke
				(width 0.1)
				(type default)
			)
			(layer "F.Fab")
		)
		(fp_line
			(start -0.2794 0.9906)
			(end 0.2794 0.9906)
			(stroke
				(width 0.1)
				(type default)
			)
			(layer "F.Fab")
		)
		(pad "1" smd rect
			(at 0 0 90)
			(size 0.508 0.508)
			(layers "F.Cu" "F.Mask" "F.Paste")
			(net "PVCCIO_CPU1")
		)
		(pad "2" smd rect
			(at 0 0.889 90)
			(size 0.508 0.508)
			(layers "F.Cu" "F.Mask" "F.Paste")
			(net "H_CPU1_MEMKLM_MEMHOT_G_N")
		)
		(zone
			(layer "F.Cu")
			(hatch none 0.5)
			(connect_pads
				(clearance 0)
			)
			(min_thickness 0.25)
			(keepout
				(tracks allowed)
				(vias not_allowed)
				(pads allowed)
				(copperpour not_allowed)
				(footprints allowed)
			)
			(placement
				(enabled no)
				(sheetname "")
			)
			(fill
				(thermal_gap 0.5)
				(thermal_bridge_width 0.5)
				(island_removal_mode 0)
			)
			(polygon
				(pts
					(xy 437.0705 -15.875) (xy 437.0705 -16.383) (xy 437.4515 -16.383) (xy 437.4515 -15.875)
				)
			)
		)
		(zone
			(layer "F.Cu")
			(hatch none 0.5)
			(connect_pads
				(clearance 0)
			)
			(min_thickness 0.25)
			(keepout
				(tracks not_allowed)
				(vias allowed)
				(pads allowed)
				(copperpour not_allowed)
				(footprints allowed)
			)
			(placement
				(enabled no)
				(sheetname "")
			)
			(fill
				(thermal_gap 0.5)
				(thermal_bridge_width 0.5)
				(island_removal_mode 0)
			)
			(polygon
				(pts
					(xy 437.4515 -15.875) (xy 437.4515 -16.383) (xy 437.0705 -16.383) (xy 437.0705 -15.875)
				)
			)
		)
	)
	(footprint ""
		(layer "F.Cu")
		(at 258.0386 -3.321812 -90)
		(property "Reference" "C5G19"
			(at 0 0 270)
			(layer "F.SilkS")
			(hide yes)
			(effects
				(font
					(size 1.27 1.27)
				)
			)
		)
		(property "Value" ""
			(at 0 0 270)
			(layer "F.Fab")
			(effects
				(font
					(size 1.27 1.27)
				)
			)
		)
		(duplicate_pad_numbers_are_jumpers no)
		(fp_rect
			(start -0.500126 1.598422)
			(end 0.500126 -0.201422)
			(stroke
				(width 0)
				(type default)
			)
			(fill no)
			(layer "F.CrtYd")
		)
		(fp_line
			(start -0.500126 1.598422)
			(end -0.500126 -0.201422)
			(stroke
				(width 0.1)
				(type default)
			)
			(layer "F.Fab")
		)
		(fp_line
			(start 0.500126 1.598422)
			(end -0.500126 1.598422)
			(stroke
				(width 0.1)
				(type default)
			)
			(layer "F.Fab")
		)
		(fp_line
			(start -0.500126 -0.201422)
			(end 0.500126 -0.201422)
			(stroke
				(width 0.1)
				(type default)
			)
			(layer "F.Fab")
		)
		(fp_line
			(start 0.500126 -0.201422)
			(end 0.500126 1.598422)
			(stroke
				(width 0.1)
				(type default)
			)
			(layer "F.Fab")
		)
		(pad "1" smd rect
			(at 0 0 180)
			(size 0.889 0.9906)
			(layers "F.Cu" "F.Mask" "F.Paste")
			(net "PVDDQ_ABC")
		)
		(pad "2" smd rect
			(at 0 1.397 180)
			(size 0.889 0.9906)
			(layers "F.Cu" "F.Mask" "F.Paste")
			(net "GND")
		)
		(zone
			(layer "F.Cu")
			(hatch none 0.5)
			(connect_pads
				(clearance 0)
			)
			(min_thickness 0.25)
			(keepout
				(tracks not_allowed)
				(vias allowed)
				(pads allowed)
				(copperpour not_allowed)
				(footprints allowed)
			)
			(placement
				(enabled no)
				(sheetname "")
			)
			(fill
				(thermal_gap 0.5)
				(thermal_bridge_width 0.5)
				(island_removal_mode 0)
			)
			(polygon
				(pts
					(xy 257.0861 -3.817112) (xy 257.0861 -2.826512) (xy 257.5941 -2.826512) (xy 257.5941 -3.817112)
				)
			)
		)
		(zone
			(layer "F.Cu")
			(hatch none 0.5)
			(connect_pads
				(clearance 0)
			)
			(min_thickness 0.25)
			(keepout
				(tracks allowed)
				(vias not_allowed)
				(pads allowed)
				(copperpour not_allowed)
				(footprints allowed)
			)
			(placement
				(enabled no)
				(sheetname "")
			)
			(fill
				(thermal_gap 0.5)
				(thermal_bridge_width 0.5)
				(island_removal_mode 0)
			)
			(polygon
				(pts
					(xy 257.0861 -3.817112) (xy 257.0861 -2.826512) (xy 257.5941 -2.826512) (xy 257.5941 -3.817112)
				)
			)
		)
	)
	(footprint ""
		(layer "F.Cu")
		(at 434.6702 -17.5006)
		(property "Reference" "R1U61"
			(at 0 0 0)
			(layer "F.SilkS")
			(hide yes)
			(effects
				(font
					(size 1.27 1.27)
				)
			)
		)
		(property "Value" ""
			(at 0 0 0)
			(layer "F.Fab")
			(effects
				(font
					(size 1.27 1.27)
				)
			)
		)
		(duplicate_pad_numbers_are_jumpers no)
		(fp_poly
			(pts
				(xy -0.2794 -0.1016) (xy 0.2794 -0.1016) (xy 0.2794 0.9906) (xy -0.2794 0.9906)
			)
			(stroke
				(width 0)
				(type default)
			)
			(fill no)
			(layer "F.CrtYd")
		)
		(fp_line
			(start -0.2794 -0.1016)
			(end -0.2794 0.9906)
			(stroke
				(width 0.1)
				(type default)
			)
			(layer "F.Fab")
		)
		(fp_line
			(start -0.2794 0.9906)
			(end 0.2794 0.9906)
			(stroke
				(width 0.1)
				(type default)
			)
			(layer "F.Fab")
		)
		(fp_line
			(start 0.2794 -0.1016)
			(end -0.2794 -0.1016)
			(stroke
				(width 0.1)
				(type default)
			)
			(layer "F.Fab")
		)
		(fp_line
			(start 0.2794 0.9906)
			(end 0.2794 -0.1016)
			(stroke
				(width 0.1)
				(type default)
			)
			(layer "F.Fab")
		)
		(pad "1" smd rect
			(at 0 0)
			(size 0.508 0.508)
			(layers "F.Cu" "F.Mask" "F.Paste")
			(net "H_CPU1_MEMKLM_MEMHOT_LVT3_K_N")
		)
		(pad "2" smd rect
			(at 0 0.889)
			(size 0.508 0.508)
			(layers "F.Cu" "F.Mask" "F.Paste")
			(net "H_CPU1_MEMKLM_MEMHOT_G_PCH_N")
		)
		(zone
			(layer "F.Cu")
			(hatch none 0.5)
			(connect_pads
				(clearance 0)
			)
			(min_thickness 0.25)
			(keepout
				(tracks allowed)
				(vias not_allowed)
				(pads allowed)
				(copperpour not_allowed)
				(footprints allowed)
			)
			(placement
				(enabled no)
				(sheetname "")
			)
			(fill
				(thermal_gap 0.5)
				(thermal_bridge_width 0.5)
				(island_removal_mode 0)
			)
			(polygon
				(pts
					(xy 434.4162 -17.2466) (xy 434.9242 -17.2466) (xy 434.9242 -16.8656) (xy 434.4162 -16.8656)
				)
			)
		)
		(zone
			(layer "F.Cu")
			(hatch none 0.5)
			(connect_pads
				(clearance 0)
			)
			(min_thickness 0.25)
			(keepout
				(tracks not_allowed)
				(vias allowed)
				(pads allowed)
				(copperpour not_allowed)
				(footprints allowed)
			)
			(placement
				(enabled no)
				(sheetname "")
			)
			(fill
				(thermal_gap 0.5)
				(thermal_bridge_width 0.5)
				(island_removal_mode 0)
			)
			(polygon
				(pts
					(xy 434.4162 -16.8656) (xy 434.9242 -16.8656) (xy 434.9242 -17.2466) (xy 434.4162 -17.2466)
				)
			)
		)
	)
	(footprint ""
		(layer "F.Cu")
		(at 14.1224 -37.719 -90)
		(property "Reference" "R1F9"
			(at 0 0 270)
			(layer "F.SilkS")
			(hide yes)
			(effects
				(font
					(size 1.27 1.27)
				)
			)
		)
		(property "Value" ""
			(at 0 0 270)
			(layer "F.Fab")
			(effects
				(font
					(size 1.27 1.27)
				)
			)
		)
		(duplicate_pad_numbers_are_jumpers no)
		(fp_poly
			(pts
				(xy -0.2794 -0.1016) (xy 0.2794 -0.1016) (xy 0.2794 0.9906) (xy -0.2794 0.9906)
			)
			(stroke
				(width 0)
				(type default)
			)
			(fill no)
			(layer "F.CrtYd")
		)
		(fp_line
			(start -0.2794 0.9906)
			(end 0.2794 0.9906)
			(stroke
				(width 0.1)
				(type default)
			)
			(layer "F.Fab")
		)
		(fp_line
			(start 0.2794 0.9906)
			(end 0.2794 -0.1016)
			(stroke
				(width 0.1)
				(type default)
			)
			(layer "F.Fab")
		)
		(fp_line
			(start -0.2794 -0.1016)
			(end -0.2794 0.9906)
			(stroke
				(width 0.1)
				(type default)
			)
			(layer "F.Fab")
		)
		(fp_line
			(start 0.2794 -0.1016)
			(end -0.2794 -0.1016)
			(stroke
				(width 0.1)
				(type default)
			)
			(layer "F.Fab")
		)
		(pad "1" smd rect
			(at 0 0 270)
			(size 0.508 0.508)
			(layers "F.Cu" "F.Mask" "F.Paste")
			(net "FM_BMC_READY_N")
		)
		(pad "2" smd rect
			(at 0 0.889 270)
			(size 0.508 0.508)
			(layers "F.Cu" "F.Mask" "F.Paste")
			(net "FAN_PWM_OUT_SYS0_R1")
		)
		(zone
			(layer "F.Cu")
			(hatch none 0.5)
			(connect_pads
				(clearance 0)
			)
			(min_thickness 0.25)
			(keepout
				(tracks not_allowed)
				(vias allowed)
				(pads allowed)
				(copperpour not_allowed)
				(footprints allowed)
			)
			(placement
				(enabled no)
				(sheetname "")
			)
			(fill
				(thermal_gap 0.5)
				(thermal_bridge_width 0.5)
				(island_removal_mode 0)
			)
			(polygon
				(pts
					(xy 13.4874 -37.973) (xy 13.4874 -37.465) (xy 13.8684 -37.465) (xy 13.8684 -37.973)
				)
			)
		)
		(zone
			(layer "F.Cu")
			(hatch none 0.5)
			(connect_pads
				(clearance 0)
			)
			(min_thickness 0.25)
			(keepout
				(tracks allowed)
				(vias not_allowed)
				(pads allowed)
				(copperpour not_allowed)
				(footprints allowed)
			)
			(placement
				(enabled no)
				(sheetname "")
			)
			(fill
				(thermal_gap 0.5)
				(thermal_bridge_width 0.5)
				(island_removal_mode 0)
			)
			(polygon
				(pts
					(xy 13.8684 -37.973) (xy 13.8684 -37.465) (xy 13.4874 -37.465) (xy 13.4874 -37.973)
				)
			)
		)
	)
)
